(kicad_pcb
	(version 20260206)
	(generator "pcbnew")
	(generator_version "10.0")
	(general
		(thickness 1.6)
		(legacy_teardrops no)
	)
	(paper "A4")
	(title_block
		(title "Bryce Canyon_R.DPB_16317-1_OCP.brd")
		(comment 1 "Bryce Canyon / footprints 259-265 of 2099")
	)
	(layers
		(0 "F.Cu" signal "TOP")
		(4 "In1.Cu" signal "L2GND")
		(6 "In2.Cu" signal "L3")
		(8 "In3.Cu" signal "L4VCC")
		(10 "In4.Cu" signal "L5VCC")
		(12 "In5.Cu" signal "L6")
		(14 "In6.Cu" signal "L7GND")
		(2 "B.Cu" signal "BOTTOM")
		(9 "F.Adhes" user "F.Adhesive")
		(11 "B.Adhes" user "B.Adhesive")
		(13 "F.Paste" user "Package Geometry/Pastemask Top")
		(15 "B.Paste" user "Package Geometry/Pastemask Bottom")
		(5 "F.SilkS" user "Ref Des/Silkscreen Top")
		(7 "B.SilkS" user "Ref Des/Silkscreen Bottom")
		(1 "F.Mask" user "Board Geometry/Soldermask Top")
		(3 "B.Mask" user "Board Geometry/Soldermask Bottom")
		(17 "Dwgs.User" user "User.Drawings")
		(19 "Cmts.User" user "User.Comments")
		(21 "Eco1.User" user "User.Eco1")
		(23 "Eco2.User" user "User.Eco2")
		(25 "Edge.Cuts" user "Board Geometry/Outline")
		(27 "Margin" user)
		(31 "F.CrtYd" user "Package Geometry/Place Bound Top")
		(29 "B.CrtYd" user "Package Geometry/Place Bound Bottom")
		(35 "F.Fab" user "Ref Des/Assembly Top")
		(33 "B.Fab" user "Ref Des/Assembly Bottom")
	)
	(footprint ""
		(layer "F.Cu")
		(at 83.566 -134.493 180)
		(property "Reference" "Q59"
			(at 0 0 180)
			(layer "F.SilkS")
			(hide yes)
			(effects
				(font
					(size 1.27 1.27)
				)
			)
		)
		(property "Value" "2N7002KDW-GP"
			(at -2.3622 -8.2042 180)
			(unlocked yes)
			(layer "F.Fab")
			(hide yes)
			(effects
				(font
					(size 1.016 1.016)
					(thickness 0.1524)
				)
			)
		)
		(property "Device Type" "SOT-363H44"
			(at -2.3622 -10.1092 180)
			(unlocked yes)
			(layer "F.Fab")
			(hide yes)
			(effects
				(font
					(size 1.016 1.016)
					(thickness 0.1524)
				)
			)
		)
		(duplicate_pad_numbers_are_jumpers no)
		(fp_line
			(start 1.4478 1.7018)
			(end 1.4478 -1.7018)
			(stroke
				(width 0.1524)
				(type default)
			)
			(layer "F.SilkS")
		)
		(fp_line
			(start 1.4478 -1.7018)
			(end -1.4478 -1.7018)
			(stroke
				(width 0.1524)
				(type default)
			)
			(layer "F.SilkS")
		)
		(fp_line
			(start -1.27 1.524)
			(end -1.27 0.6604)
			(stroke
				(width 0.4826)
				(type default)
			)
			(layer "F.SilkS")
		)
		(fp_line
			(start -1.4478 1.7018)
			(end 1.4478 1.7018)
			(stroke
				(width 0.1524)
				(type default)
			)
			(layer "F.SilkS")
		)
		(fp_line
			(start -1.4478 -1.7018)
			(end -1.4478 1.7018)
			(stroke
				(width 0.1524)
				(type default)
			)
			(layer "F.SilkS")
		)
		(fp_poly
			(pts
				(xy -1.524 -1.778) (xy 1.524 -1.778) (xy 1.524 1.778) (xy -1.524 1.778)
			)
			(stroke
				(width 0)
				(type default)
			)
			(fill no)
			(layer "F.CrtYd")
		)
		(fp_poly
			(pts
				(xy -1.524 -1.778) (xy 1.524 -1.778) (xy 1.524 1.778) (xy -1.524 1.778)
			)
			(stroke
				(width 0)
				(type default)
			)
			(fill no)
			(layer "F.Fab")
		)
		(pad "1" smd rect
			(at -0.65024 0.9398 180)
			(size 0.4064 1.016)
			(layers "F.Cu" "F.Mask" "F.Paste")
			(net "GND")
		)
		(pad "2" smd rect
			(at 0 0.9398 180)
			(size 0.4064 1.016)
			(layers "F.Cu" "F.Mask" "F.Paste")
			(net "SW_PWR_R_HDD14")
		)
		(pad "3" smd rect
			(at 0.65024 0.9398 180)
			(size 0.4064 1.016)
			(layers "F.Cu" "F.Mask" "F.Paste")
			(net "SW_HDD_P14")
		)
		(pad "4" smd rect
			(at 0.65024 -0.9398 180)
			(size 0.4064 1.016)
			(layers "F.Cu" "F.Mask" "F.Paste")
			(net "GND")
		)
		(pad "5" smd rect
			(at 0 -0.9398 180)
			(size 0.4064 1.016)
			(layers "F.Cu" "F.Mask" "F.Paste")
			(net "SW_HDD_G14")
		)
		(pad "6" smd rect
			(at -0.65024 -0.9398 180)
			(size 0.4064 1.016)
			(layers "F.Cu" "F.Mask" "F.Paste")
			(net "SW_HDD_R14")
		)
	)
	(footprint ""
		(layer "F.Cu")
		(at 32.463486 -244.660674 90)
		(property "Reference" "C497"
			(at 0 0 90)
			(layer "F.SilkS")
			(hide yes)
			(effects
				(font
					(size 1.27 1.27)
				)
			)
		)
		(property "Value" "SCD01U16V1KX-GP"
			(at -2.8321 -1.7399 90)
			(unlocked yes)
			(layer "F.Fab")
			(hide yes)
			(effects
				(font
					(size 1.016 1.016)
					(thickness 0.1524)
				)
			)
		)
		(property "Device Type" "C0201H13"
			(at -2.8321 -3.2639 90)
			(unlocked yes)
			(layer "F.Fab")
			(hide yes)
			(effects
				(font
					(size 1.016 1.016)
					(thickness 0.1524)
				)
			)
		)
		(duplicate_pad_numbers_are_jumpers no)
		(fp_rect
			(start -0.2794 0.6477)
			(end 0.2794 -0.6477)
			(stroke
				(width 0)
				(type default)
			)
			(fill no)
			(layer "F.CrtYd")
		)
		(fp_rect
			(start -0.2794 0.6477)
			(end 0.2794 -0.6477)
			(stroke
				(width 0)
				(type default)
			)
			(fill no)
			(layer "F.Fab")
		)
		(pad "1" smd custom
			(at 0 -0.2794 90)
			(size 0.0762 0.0762)
			(layers "F.Cu" "F.Mask" "F.Paste")
			(net "SAS_HDD_RX_P0")
			(options
				(clearance outline)
				(anchor circle)
			)
			(primitives
				(gr_poly
					(pts
						(arc
							(start 0.1524 -0.127)
							(mid 0.137521 -0.162921)
							(end 0.1016 -0.1778)
						)
						(arc
							(start -0.1016 -0.1778)
							(mid -0.137521 -0.162921)
							(end -0.1524 -0.127)
						)
						(arc
							(start -0.1524 0.127)
							(mid -0.137521 0.162921)
							(end -0.1016 0.1778)
						)
						(arc
							(start 0.1016 0.1778)
							(mid 0.137521 0.162921)
							(end 0.1524 0.127)
						)
					)
					(width 0)
					(fill yes)
				)
			)
		)
		(pad "2" smd custom
			(at 0 0.2794 90)
			(size 0.0762 0.0762)
			(layers "F.Cu" "F.Mask" "F.Paste")
			(net "PHY_SCC_B_TO_DRV_B_0_DP")
			(options
				(clearance outline)
				(anchor circle)
			)
			(primitives
				(gr_poly
					(pts
						(arc
							(start 0.1524 -0.127)
							(mid 0.137521 -0.162921)
							(end 0.1016 -0.1778)
						)
						(arc
							(start -0.1016 -0.1778)
							(mid -0.137521 -0.162921)
							(end -0.1524 -0.127)
						)
						(arc
							(start -0.1524 0.127)
							(mid -0.137521 0.162921)
							(end -0.1016 0.1778)
						)
						(arc
							(start 0.1016 0.1778)
							(mid 0.137521 0.162921)
							(end 0.1524 0.127)
						)
					)
					(width 0)
					(fill yes)
				)
			)
		)
	)
	(footprint ""
		(layer "F.Cu")
		(at 209.804 -226.822 90)
		(property "Reference" "R18"
			(at 0 0 90)
			(layer "F.SilkS")
			(hide yes)
			(effects
				(font
					(size 1.27 1.27)
				)
			)
		)
		(property "Value" "4K7R2F-GP"
			(at 0.064008 -3.993896 90)
			(unlocked yes)
			(layer "F.Fab")
			(hide yes)
			(effects
				(font
					(size 1.016 1.016)
					(thickness 0.1524)
				)
			)
		)
		(property "Device Type" "R402H16"
			(at 0.064008 -5.517896 90)
			(unlocked yes)
			(layer "F.Fab")
			(hide yes)
			(effects
				(font
					(size 1.016 1.016)
					(thickness 0.1524)
				)
			)
		)
		(duplicate_pad_numbers_are_jumpers no)
		(fp_line
			(start 0.508 -0.9398)
			(end -0.508 -0.9398)
			(stroke
				(width 0.1524)
				(type default)
			)
			(layer "F.SilkS")
		)
		(fp_line
			(start -0.508 -0.9398)
			(end -0.508 0.9398)
			(stroke
				(width 0.1524)
				(type default)
			)
			(layer "F.SilkS")
		)
		(fp_rect
			(start -0.508 0.9398)
			(end 0.508 -0.9398)
			(stroke
				(width 0)
				(type default)
			)
			(fill no)
			(layer "F.CrtYd")
		)
		(fp_rect
			(start -0.508 0.9398)
			(end 0.508 -0.9398)
			(stroke
				(width 0)
				(type default)
			)
			(fill no)
			(layer "F.Fab")
		)
		(pad "1" smd custom
			(at 0 -0.4445 90)
			(size 0.1397 0.1397)
			(layers "F.Cu" "F.Mask" "F.Paste")
			(net "P3V3_STBY_B")
			(options
				(clearance outline)
				(anchor circle)
			)
			(primitives
				(gr_poly
					(pts
						(arc
							(start -0.1778 -0.2794)
							(mid -0.249642 -0.249642)
							(end -0.2794 -0.1778)
						)
						(arc
							(start -0.2794 0.1778)
							(mid -0.249642 0.249642)
							(end -0.1778 0.2794)
						)
						(arc
							(start 0.1778 0.2794)
							(mid 0.249642 0.249642)
							(end 0.2794 0.1778)
						)
						(arc
							(start 0.2794 -0.1778)
							(mid 0.249642 -0.249642)
							(end 0.1778 -0.2794)
						)
					)
					(width 0)
					(fill yes)
				)
			)
		)
		(pad "2" smd custom
			(at 0 0.4445 90)
			(size 0.1397 0.1397)
			(layers "F.Cu" "F.Mask" "F.Paste")
			(net "IO_EXP1_HDD_FAULT_A1")
			(options
				(clearance outline)
				(anchor circle)
			)
			(primitives
				(gr_poly
					(pts
						(arc
							(start -0.1778 -0.2794)
							(mid -0.249642 -0.249642)
							(end -0.2794 -0.1778)
						)
						(arc
							(start -0.2794 0.1778)
							(mid -0.249642 0.249642)
							(end -0.1778 0.2794)
						)
						(arc
							(start 0.1778 0.2794)
							(mid 0.249642 0.249642)
							(end 0.2794 0.1778)
						)
						(arc
							(start 0.2794 -0.1778)
							(mid 0.249642 -0.249642)
							(end 0.1778 -0.2794)
						)
					)
					(width 0)
					(fill yes)
				)
			)
		)
	)
	(footprint ""
		(layer "F.Cu")
		(at 231.41432 -219.04198 180)
		(property "Reference" "R68"
			(at 0 0 180)
			(layer "F.SilkS")
			(hide yes)
			(effects
				(font
					(size 1.27 1.27)
				)
			)
		)
		(property "Value" "4K7R2F-GP"
			(at 0.064008 -3.993896 180)
			(unlocked yes)
			(layer "F.Fab")
			(hide yes)
			(effects
				(font
					(size 1.016 1.016)
					(thickness 0.1524)
				)
			)
		)
		(property "Device Type" "R402H16"
			(at 0.064008 -5.517896 180)
			(unlocked yes)
			(layer "F.Fab")
			(hide yes)
			(effects
				(font
					(size 1.016 1.016)
					(thickness 0.1524)
				)
			)
		)
		(duplicate_pad_numbers_are_jumpers no)
		(fp_line
			(start 0.508 -0.9398)
			(end -0.508 -0.9398)
			(stroke
				(width 0.1524)
				(type default)
			)
			(layer "F.SilkS")
		)
		(fp_line
			(start -0.508 -0.9398)
			(end -0.508 0.9398)
			(stroke
				(width 0.1524)
				(type default)
			)
			(layer "F.SilkS")
		)
		(fp_rect
			(start -0.508 0.9398)
			(end 0.508 -0.9398)
			(stroke
				(width 0)
				(type default)
			)
			(fill no)
			(layer "F.CrtYd")
		)
		(fp_rect
			(start -0.508 0.9398)
			(end 0.508 -0.9398)
			(stroke
				(width 0)
				(type default)
			)
			(fill no)
			(layer "F.Fab")
		)
		(pad "1" smd custom
			(at 0 -0.4445 180)
			(size 0.1397 0.1397)
			(layers "F.Cu" "F.Mask" "F.Paste")
			(net "P3V3_STBY_B")
			(options
				(clearance outline)
				(anchor circle)
			)
			(primitives
				(gr_poly
					(pts
						(arc
							(start -0.1778 -0.2794)
							(mid -0.249642 -0.249642)
							(end -0.2794 -0.1778)
						)
						(arc
							(start -0.2794 0.1778)
							(mid -0.249642 0.249642)
							(end -0.1778 0.2794)
						)
						(arc
							(start 0.1778 0.2794)
							(mid 0.249642 0.249642)
							(end 0.2794 0.1778)
						)
						(arc
							(start 0.2794 -0.1778)
							(mid 0.249642 -0.249642)
							(end 0.1778 -0.2794)
						)
					)
					(width 0)
					(fill yes)
				)
			)
		)
		(pad "2" smd custom
			(at 0 0.4445 180)
			(size 0.1397 0.1397)
			(layers "F.Cu" "F.Mask" "F.Paste")
			(net "IO_EXP1_A0")
			(options
				(clearance outline)
				(anchor circle)
			)
			(primitives
				(gr_poly
					(pts
						(arc
							(start -0.1778 -0.2794)
							(mid -0.249642 -0.249642)
							(end -0.2794 -0.1778)
						)
						(arc
							(start -0.2794 0.1778)
							(mid -0.249642 0.249642)
							(end -0.1778 0.2794)
						)
						(arc
							(start 0.1778 0.2794)
							(mid 0.249642 0.249642)
							(end 0.2794 0.1778)
						)
						(arc
							(start 0.2794 -0.1778)
							(mid 0.249642 -0.249642)
							(end 0.1778 -0.2794)
						)
					)
					(width 0)
					(fill yes)
				)
			)
		)
	)
	(footprint ""
		(layer "F.Cu")
		(at 18.227802 -226.57435 -90)
		(property "Reference" "R1112"
			(at 0 0 270)
			(layer "F.SilkS")
			(hide yes)
			(effects
				(font
					(size 1.27 1.27)
				)
			)
		)
		(property "Value" "309KR2F-GP"
			(at 0.064008 -3.993896 270)
			(unlocked yes)
			(layer "F.Fab")
			(hide yes)
			(effects
				(font
					(size 1.016 1.016)
					(thickness 0.1524)
				)
			)
		)
		(property "Device Type" "R402H16"
			(at 0.064008 -5.517896 270)
			(unlocked yes)
			(layer "F.Fab")
			(hide yes)
			(effects
				(font
					(size 1.016 1.016)
					(thickness 0.1524)
				)
			)
		)
		(duplicate_pad_numbers_are_jumpers no)
		(fp_line
			(start -0.508 -0.9398)
			(end -0.508 0.9398)
			(stroke
				(width 0.1524)
				(type default)
			)
			(layer "F.SilkS")
		)
		(fp_line
			(start 0.508 -0.9398)
			(end -0.508 -0.9398)
			(stroke
				(width 0.1524)
				(type default)
			)
			(layer "F.SilkS")
		)
		(fp_rect
			(start -0.508 0.9398)
			(end 0.508 -0.9398)
			(stroke
				(width 0)
				(type default)
			)
			(fill no)
			(layer "F.CrtYd")
		)
		(fp_rect
			(start -0.508 0.9398)
			(end 0.508 -0.9398)
			(stroke
				(width 0)
				(type default)
			)
			(fill no)
			(layer "F.Fab")
		)
		(pad "1" smd custom
			(at 0 -0.4445 270)
			(size 0.1397 0.1397)
			(layers "F.Cu" "F.Mask" "F.Paste")
			(net "P5V_B_1_RF")
			(options
				(clearance outline)
				(anchor circle)
			)
			(primitives
				(gr_poly
					(pts
						(arc
							(start -0.1778 -0.2794)
							(mid -0.249642 -0.249642)
							(end -0.2794 -0.1778)
						)
						(arc
							(start -0.2794 0.1778)
							(mid -0.249642 0.249642)
							(end -0.1778 0.2794)
						)
						(arc
							(start 0.1778 0.2794)
							(mid 0.249642 0.249642)
							(end 0.2794 0.1778)
						)
						(arc
							(start 0.2794 -0.1778)
							(mid 0.249642 -0.249642)
							(end 0.1778 -0.2794)
						)
					)
					(width 0)
					(fill yes)
				)
			)
		)
		(pad "2" smd custom
			(at 0 0.4445 270)
			(size 0.1397 0.1397)
			(layers "F.Cu" "F.Mask" "F.Paste")
			(net "P5V_B_1_VREG")
			(options
				(clearance outline)
				(anchor circle)
			)
			(primitives
				(gr_poly
					(pts
						(arc
							(start -0.1778 -0.2794)
							(mid -0.249642 -0.249642)
							(end -0.2794 -0.1778)
						)
						(arc
							(start -0.2794 0.1778)
							(mid -0.249642 0.249642)
							(end -0.1778 0.2794)
						)
						(arc
							(start 0.1778 0.2794)
							(mid 0.249642 0.249642)
							(end 0.2794 0.1778)
						)
						(arc
							(start 0.2794 -0.1778)
							(mid 0.249642 -0.249642)
							(end 0.1778 -0.2794)
						)
					)
					(width 0)
					(fill yes)
				)
			)
		)
	)
	(footprint ""
		(layer "F.Cu")
		(at 203.5302 -307.8226)
		(property "Reference" "TC6"
			(at 0 0 0)
			(layer "F.SilkS")
			(hide yes)
			(effects
				(font
					(size 1.27 1.27)
				)
			)
		)
		(property "Value" "SE270U16VM-8-GP"
			(at -4.5974 -2.54 0)
			(unlocked yes)
			(layer "F.Fab")
			(hide yes)
			(effects
				(font
					(size 1.016 1.016)
					(thickness 0.1524)
				)
			)
		)
		(property "Device Type" "SE361416H394"
			(at -4.5974 -4.064 0)
			(unlocked yes)
			(layer "F.Fab")
			(hide yes)
			(effects
				(font
					(size 1.016 1.016)
					(thickness 0.1524)
				)
			)
		)
		(duplicate_pad_numbers_are_jumpers no)
		(fp_line
			(start -3.556 -3.4163)
			(end -2.3622 -4.6101)
			(stroke
				(width 0.1524)
				(type default)
			)
			(layer "F.SilkS")
		)
		(fp_line
			(start -3.556 4.6101)
			(end -3.556 -3.4163)
			(stroke
				(width 0.1524)
				(type default)
			)
			(layer "F.SilkS")
		)
		(fp_line
			(start -2.3622 -4.6101)
			(end 2.3622 -4.6101)
			(stroke
				(width 0.1524)
				(type default)
			)
			(layer "F.SilkS")
		)
		(fp_line
			(start 2.3622 -4.6101)
			(end 3.556 -3.4163)
			(stroke
				(width 0.1524)
				(type default)
			)
			(layer "F.SilkS")
		)
		(fp_line
			(start 3.556 -3.4163)
			(end 3.556 4.6101)
			(stroke
				(width 0.1524)
				(type default)
			)
			(layer "F.SilkS")
		)
		(fp_line
			(start 3.556 4.6101)
			(end -3.556 4.6101)
			(stroke
				(width 0.1524)
				(type default)
			)
			(layer "F.SilkS")
		)
		(fp_rect
			(start -3.302 3.6449)
			(end 3.302 -3.6449)
			(stroke
				(width 0)
				(type default)
			)
			(fill no)
			(layer "F.CrtYd")
		)
		(fp_poly
			(pts
				(xy 3.81 4.6863) (xy 3.81 -3.4925) (xy 3.302 -3.4925) (xy 3.302 3.6449) (xy -3.302 3.6449) (xy -3.302 -3.6449)
				(xy 3.302 -3.6449) (xy 3.302 -3.5052) (xy 3.81 -3.5052) (xy 3.81 -4.6863) (xy -3.81 -4.6863) (xy -3.81 4.6863)
			)
			(stroke
				(width 0)
				(type default)
			)
			(fill no)
			(layer "F.CrtYd")
		)
		(fp_rect
			(start -3.81 4.6863)
			(end 3.81 -4.6863)
			(stroke
				(width 0)
				(type default)
			)
			(fill no)
			(layer "F.Fab")
		)
		(pad "1" smd rect
			(at 0 -2.574036)
			(size 1.4224 3.556)
			(layers "F.Cu" "F.Mask" "F.Paste")
			(net "P12V_B")
		)
		(pad "2" smd rect
			(at 0 2.574036)
			(size 1.4224 3.556)
			(layers "F.Cu" "F.Mask" "F.Paste")
			(net "GND")
		)
	)
	(footprint ""
		(layer "F.Cu")
		(at 348.582996 -363.22 90)
		(property "Reference" "C531"
			(at 0 0 90)
			(layer "F.SilkS")
			(hide yes)
			(effects
				(font
					(size 1.27 1.27)
				)
			)
		)
		(property "Value" "SC1U25V3KX-GP"
			(at 0 -2.8194 90)
			(unlocked yes)
			(layer "F.Fab")
			(hide yes)
			(effects
				(font
					(size 1.016 1.016)
					(thickness 0.1524)
				)
			)
		)
		(property "Device Type" "C603H36"
			(at 0 -4.3434 90)
			(unlocked yes)
			(layer "F.Fab")
			(hide yes)
			(effects
				(font
					(size 1.016 1.016)
					(thickness 0.1524)
				)
			)
		)
		(duplicate_pad_numbers_are_jumpers no)
		(fp_line
			(start 0.508 0)
			(end -0.508 0)
			(stroke
				(width 0.2032)
				(type default)
			)
			(layer "F.SilkS")
		)
		(fp_rect
			(start -0.5842 1.3335)
			(end 0.5842 -1.3335)
			(stroke
				(width 0)
				(type default)
			)
			(fill no)
			(layer "F.CrtYd")
		)
		(fp_rect
			(start -0.5842 1.3335)
			(end 0.5842 -1.3335)
			(stroke
				(width 0)
				(type default)
			)
			(fill no)
			(layer "F.Fab")
		)
		(pad "1" smd custom
			(at 0 -0.762 90)
			(size 0.2159 0.2159)
			(layers "F.Cu" "F.Mask" "F.Paste")
			(net "P12V_FAN2")
			(options
				(clearance outline)
				(anchor circle)
			)
			(primitives
				(gr_poly
					(pts
						(arc
							(start -0.3302 -0.4318)
							(mid -0.402042 -0.402042)
							(end -0.4318 -0.3302)
						)
						(arc
							(start -0.4318 0.3302)
							(mid -0.402042 0.402042)
							(end -0.3302 0.4318)
						)
						(arc
							(start 0.3302 0.4318)
							(mid 0.402042 0.402042)
							(end 0.4318 0.3302)
						)
						(arc
							(start 0.4318 -0.3302)
							(mid 0.402042 -0.402042)
							(end 0.3302 -0.4318)
						)
					)
					(width 0)
					(fill yes)
				)
			)
		)
		(pad "2" smd custom
			(at 0 0.762 90)
			(size 0.2159 0.2159)
			(layers "F.Cu" "F.Mask" "F.Paste")
			(net "GND")
			(options
				(clearance outline)
				(anchor circle)
			)
			(primitives
				(gr_poly
					(pts
						(arc
							(start -0.3302 -0.4318)
							(mid -0.402042 -0.402042)
							(end -0.4318 -0.3302)
						)
						(arc
							(start -0.4318 0.3302)
							(mid -0.402042 0.402042)
							(end -0.3302 0.4318)
						)
						(arc
							(start 0.3302 0.4318)
							(mid 0.402042 0.402042)
							(end 0.4318 0.3302)
						)
						(arc
							(start 0.4318 -0.3302)
							(mid 0.402042 -0.402042)
							(end 0.3302 -0.4318)
						)
					)
					(width 0)
					(fill yes)
				)
			)
		)
	)
)
